# TIMECARD (Time Appliance Project (Time Card)) — schematic netlist excerpt (pin names and nets, part order shuffled) for the footprints in the layout excerpt that follows; sources: Cadence DE-HDL packaged netlist, KiCad conversion of R4006-B0001-02_R01.brd

R57  RESISTOR  33OHM 1%  pkg SMC_0402R_H016  page 9 : \1\ = BF_PCIE_PERST_N ; \2\ = PCIE_PERST_N
R237  RESISTOR  10KOHM 1%  pkg SMC_0402R_H016  page 31 : \1\ = XP3R3V_FPGA_EN_R ; \2\ = SG

(kicad_pcb
	(version 20260206)
	(generator "pcbnew")
	(generator_version "10.0")
	(general
		(thickness 1.6)
		(legacy_teardrops no)
	)
	(paper "A4")
	(title_block
		(title "timecard-production-celestica-r4006 — R4006-B0001-02_R01.brd")
		(comment 1 "Time Appliance Project (Time Card) / footprints 543-544 of 1113")
	)
	(layers
		(0 "F.Cu" signal "TOP")
		(4 "In1.Cu" signal "L02_GND1")
		(6 "In2.Cu" signal "L03_SIG1")
		(8 "In3.Cu" signal "L04_GND2")
		(10 "In4.Cu" signal "L05_VCC1")
		(12 "In5.Cu" signal "L06_VCC2")
		(14 "In6.Cu" signal "L07_GND3")
		(16 "In7.Cu" signal "L08_SIG2")
		(18 "In8.Cu" signal "L09_GND4")
		(2 "B.Cu" signal "BOTTOM")
		(9 "F.Adhes" user "F.Adhesive")
		(11 "B.Adhes" user "B.Adhesive")
		(13 "F.Paste" user "Package Geometry/Pastemask Top")
		(15 "B.Paste" user "Package Geometry/Pastemask Bottom")
		(5 "F.SilkS" user "Ref Des/Silkscreen Top")
		(7 "B.SilkS" user "Ref Des/Silkscreen Bottom")
		(1 "F.Mask" user "Board Geometry/Soldermask Top")
		(3 "B.Mask" user "Board Geometry/Soldermask Bottom")
		(17 "Dwgs.User" user "User.Drawings")
		(19 "Cmts.User" user "User.Comments")
		(21 "Eco1.User" user "User.Eco1")
		(23 "Eco2.User" user "User.Eco2")
		(25 "Edge.Cuts" user "Board Geometry/Outline")
		(27 "Margin" user)
		(31 "F.CrtYd" user "Package Geometry/Place Bound Top")
		(29 "B.CrtYd" user "Package Geometry/Place Bound Bottom")
		(35 "F.Fab" user "Ref Des/Assembly Top")
		(33 "B.Fab" user "Ref Des/Assembly Bottom")
	)
	(footprint ""
		(layer "F.Cu")
		(at 115.443 -72.263)
		(property "Reference" "R237"
			(at 3.429 0.16637 0)
			(unlocked yes)
			(layer "F.SilkS")
			(effects
				(font
					(size 0.7874 0.5842)
					(thickness 0.1524)
				)
			)
		)
		(property "Value" "VAL*"
			(at 0.02032 2.13233 0)
			(unlocked yes)
			(layer "F.Fab")
			(hide yes)
			(effects
				(font
					(size 0.7874 0.5842)
					(thickness 0.1524)
				)
			)
		)
		(property "Tolerance" "TOL*"
			(at 0.044704 3.05435 0)
			(unlocked yes)
			(layer "Cmts.User")
			(hide yes)
			(effects
				(font
					(size 0.7874 0.5842)
					(thickness 0.1524)
				)
			)
		)
		(property "User Part Number" "PARTNUM*"
			(at 0.02032 4.024884 0)
			(unlocked yes)
			(layer "Cmts.User")
			(hide yes)
			(effects
				(font
					(size 0.7874 0.5842)
					(thickness 0.1524)
				)
			)
		)
		(property "Device Type" "RESISTOR-G155-11002-01,10KOHM,A"
			(at 0.008382 1.210564 0)
			(unlocked yes)
			(layer "F.Fab")
			(hide yes)
			(effects
				(font
					(size 0.7874 0.5842)
					(thickness 0.1524)
				)
			)
		)
		(duplicate_pad_numbers_are_jumpers no)
		(fp_line
			(start -1.143 -0.5588)
			(end -1.143 0.5588)
			(stroke
				(width 0.1)
				(type default)
			)
			(layer "F.SilkS")
		)
		(fp_line
			(start -1.143 0.5588)
			(end 1.143 0.5588)
			(stroke
				(width 0.1)
				(type default)
			)
			(layer "F.SilkS")
		)
		(fp_line
			(start 1.143 -0.5588)
			(end -1.143 -0.5588)
			(stroke
				(width 0.1)
				(type default)
			)
			(layer "F.SilkS")
		)
		(fp_line
			(start 1.143 0.5588)
			(end 1.143 -0.5588)
			(stroke
				(width 0.1)
				(type default)
			)
			(layer "F.SilkS")
		)
		(fp_poly
			(pts
				(xy -1.143 0.5588) (xy 1.143 0.5588) (xy 1.143 -0.5588) (xy -1.143 -0.5588)
			)
			(stroke
				(width 0)
				(type default)
			)
			(fill no)
			(layer "F.CrtYd")
		)
		(fp_line
			(start -0.508 -0.3048)
			(end -0.508 0.3048)
			(stroke
				(width 0.1)
				(type default)
			)
			(layer "F.Fab")
		)
		(fp_line
			(start -0.508 0.3048)
			(end 0.508 0.3048)
			(stroke
				(width 0.1)
				(type default)
			)
			(layer "F.Fab")
		)
		(fp_line
			(start 0.508 -0.3048)
			(end -0.508 -0.3048)
			(stroke
				(width 0.1)
				(type default)
			)
			(layer "F.Fab")
		)
		(fp_line
			(start 0.508 0.3048)
			(end 0.508 -0.3048)
			(stroke
				(width 0.1)
				(type default)
			)
			(layer "F.Fab")
		)
		(pad "1" smd rect
			(at -0.5334 0)
			(size 0.7112 0.6096)
			(layers "F.Cu" "F.Mask" "F.Paste")
			(net "XP3R3V_FPGA_EN_R")
		)
		(pad "2" smd rect
			(at 0.5334 0)
			(size 0.7112 0.6096)
			(layers "F.Cu" "F.Mask" "F.Paste")
			(net "SG")
		)
		(zone
			(layer "F.Cu")
			(hatch none 0.5)
			(connect_pads
				(clearance 0)
			)
			(min_thickness 0.25)
			(keepout
				(tracks not_allowed)
				(vias allowed)
				(pads allowed)
				(copperpour not_allowed)
				(footprints allowed)
			)
			(placement
				(enabled no)
				(sheetname "")
			)
			(fill
				(thermal_gap 0.5)
				(thermal_bridge_width 0.5)
				(island_removal_mode 0)
			)
			(polygon
				(pts
					(xy 115.3668 -71.9582) (xy 115.5192 -71.9582) (xy 115.5192 -72.5678) (xy 115.3668 -72.5678)
				)
			)
		)
		(zone
			(layer "F.Cu")
			(hatch none 0.5)
			(connect_pads
				(clearance 0)
			)
			(min_thickness 0.25)
			(keepout
				(tracks allowed)
				(vias not_allowed)
				(pads allowed)
				(copperpour not_allowed)
				(footprints allowed)
			)
			(placement
				(enabled no)
				(sheetname "")
			)
			(fill
				(thermal_gap 0.5)
				(thermal_bridge_width 0.5)
				(island_removal_mode 0)
			)
			(polygon
				(pts
					(xy 115.3668 -71.9582) (xy 115.5192 -71.9582) (xy 115.5192 -72.5678) (xy 115.3668 -72.5678)
				)
			)
		)
	)
	(footprint ""
		(layer "F.Cu")
		(at 75.565 -14.590014)
		(property "Reference" "R57"
			(at 0.127 1.294384 0)
			(unlocked yes)
			(layer "F.SilkS")
			(effects
				(font
					(size 0.7874 0.5842)
					(thickness 0.1524)
				)
			)
		)
		(property "Value" "VAL*"
			(at 0.02032 2.13233 0)
			(unlocked yes)
			(layer "F.Fab")
			(hide yes)
			(effects
				(font
					(size 0.7874 0.5842)
					(thickness 0.1524)
				)
			)
		)
		(property "Tolerance" "TOL*"
			(at 0.044704 3.05435 0)
			(unlocked yes)
			(layer "Cmts.User")
			(hide yes)
			(effects
				(font
					(size 0.7874 0.5842)
					(thickness 0.1524)
				)
			)
		)
		(property "User Part Number" "PARTNUM*"
			(at 0.02032 4.024884 0)
			(unlocked yes)
			(layer "Cmts.User")
			(hide yes)
			(effects
				(font
					(size 0.7874 0.5842)
					(thickness 0.1524)
				)
			)
		)
		(property "Device Type" "RESISTOR-G155-133R0-01,33OHM,1%"
			(at 0.008382 1.210564 0)
			(unlocked yes)
			(layer "F.Fab")
			(hide yes)
			(effects
				(font
					(size 0.7874 0.5842)
					(thickness 0.1524)
				)
			)
		)
		(duplicate_pad_numbers_are_jumpers no)
		(fp_line
			(start -1.143 -0.5588)
			(end -1.143 0.5588)
			(stroke
				(width 0.1)
				(type default)
			)
			(layer "F.SilkS")
		)
		(fp_line
			(start -1.143 0.5588)
			(end 1.143 0.5588)
			(stroke
				(width 0.1)
				(type default)
			)
			(layer "F.SilkS")
		)
		(fp_line
			(start 1.143 -0.5588)
			(end -1.143 -0.5588)
			(stroke
				(width 0.1)
				(type default)
			)
			(layer "F.SilkS")
		)
		(fp_line
			(start 1.143 0.5588)
			(end 1.143 -0.5588)
			(stroke
				(width 0.1)
				(type default)
			)
			(layer "F.SilkS")
		)
		(fp_rect
			(start -1.143 0.5588)
			(end 1.143 -0.5588)
			(stroke
				(width 0)
				(type default)
			)
			(fill no)
			(layer "F.CrtYd")
		)
		(fp_line
			(start -0.508 -0.3048)
			(end -0.508 0.3048)
			(stroke
				(width 0.1)
				(type default)
			)
			(layer "F.Fab")
		)
		(fp_line
			(start -0.508 0.3048)
			(end 0.508 0.3048)
			(stroke
				(width 0.1)
				(type default)
			)
			(layer "F.Fab")
		)
		(fp_line
			(start 0.508 -0.3048)
			(end -0.508 -0.3048)
			(stroke
				(width 0.1)
				(type default)
			)
			(layer "F.Fab")
		)
		(fp_line
			(start 0.508 0.3048)
			(end 0.508 -0.3048)
			(stroke
				(width 0.1)
				(type default)
			)
			(layer "F.Fab")
		)
		(pad "1" smd rect
			(at -0.5334 0)
			(size 0.7112 0.6096)
			(layers "F.Cu" "F.Mask" "F.Paste")
			(net "BF_PCIE_PERST_N")
		)
		(pad "2" smd rect
			(at 0.5334 0)
			(size 0.7112 0.6096)
			(layers "F.Cu" "F.Mask" "F.Paste")
			(net "PCIE_PERST_N")
		)
		(zone
			(layer "F.Cu")
			(hatch none 0.5)
			(connect_pads
				(clearance 0)
			)
			(min_thickness 0.25)
			(keepout
				(tracks allowed)
				(vias not_allowed)
				(pads allowed)
				(copperpour not_allowed)
				(footprints allowed)
			)
			(placement
				(enabled no)
				(sheetname "")
			)
			(fill
				(thermal_gap 0.5)
				(thermal_bridge_width 0.5)
				(island_removal_mode 0)
			)
			(polygon
				(pts
					(xy 75.4888 -14.285214) (xy 75.6412 -14.285214) (xy 75.6412 -14.894814) (xy 75.4888 -14.894814)
				)
			)
		)
	)
)
